# T6G (Grand Teton) — schematic netlist excerpt (pin names and nets, part order shuffled) for the footprints in the layout excerpt that follows; sources: Cadence DE-HDL packaged netlist, KiCad conversion of 04192023_DAF0TMB3IC0_F0TG_MB_C_brd_V02_OCP.brd

PC2237  Q_CAP  3900PF 50V 10% X7R  pkg C0402  page 152 : A = P12V_SCM_GATE ; B = GND
R3254  Q_RES  0 5% EMPTY  pkg 0402LF  page 150 : A = TP_PCIE_TXP<3> ; B = LED_HDD_ACTIVITY_B_N

(kicad_pcb
	(version 20260206)
	(generator "pcbnew")
	(generator_version "10.0")
	(general
		(thickness 1.6)
		(legacy_teardrops no)
	)
	(paper "A4")
	(title_block
		(title "04192023_DAF0TMB3IC0_F0TG_MB_C_brd_V02_OCP.brd")
		(comment 1 "Grand Teton / footprints 635-636 of 8354")
	)
	(layers
		(0 "F.Cu" signal "TOP")
		(4 "In1.Cu" signal "GND")
		(6 "In2.Cu" signal "IN1")
		(8 "In3.Cu" signal "GND1")
		(10 "In4.Cu" signal "IN2")
		(12 "In5.Cu" signal "GND2")
		(14 "In6.Cu" signal "IN3")
		(16 "In7.Cu" signal "GND3")
		(18 "In8.Cu" signal "VCC")
		(20 "In9.Cu" signal "VCC1")
		(22 "In10.Cu" signal "GND4")
		(24 "In11.Cu" signal "IN4")
		(26 "In12.Cu" signal "GND5")
		(28 "In13.Cu" signal "IN5")
		(30 "In14.Cu" signal "GND6")
		(32 "In15.Cu" signal "IN6")
		(34 "In16.Cu" signal "GND7")
		(2 "B.Cu" signal "BOTTOM")
		(9 "F.Adhes" user "F.Adhesive")
		(11 "B.Adhes" user "B.Adhesive")
		(13 "F.Paste" user "Package Geometry/Pastemask Top")
		(15 "B.Paste" user "Package Geometry/Pastemask Bottom")
		(5 "F.SilkS" user "Ref Des/Silkscreen Top")
		(7 "B.SilkS" user "Ref Des/Silkscreen Bottom")
		(1 "F.Mask" user "Board Geometry/Soldermask Top")
		(3 "B.Mask" user "Board Geometry/Soldermask Bottom")
		(17 "Dwgs.User" user "User.Drawings")
		(19 "Cmts.User" user "User.Comments")
		(21 "Eco1.User" user "User.Eco1")
		(23 "Eco2.User" user "User.Eco2")
		(25 "Edge.Cuts" user "Board Geometry/Outline")
		(27 "Margin" user)
		(31 "F.CrtYd" user "Package Geometry/Place Bound Top")
		(29 "B.CrtYd" user "Package Geometry/Place Bound Bottom")
		(35 "F.Fab" user "Ref Des/Assembly Top")
		(33 "B.Fab" user "Ref Des/Assembly Bottom")
	)
	(footprint ""
		(layer "F.Cu")
		(at 191.295782 -28.267152)
		(property "Reference" "PC2237"
			(at 0 0 0)
			(layer "F.SilkS")
			(hide yes)
			(effects
				(font
					(size 1.27 1.27)
				)
			)
		)
		(property "Value" ""
			(at 0 0 0)
			(layer "F.Fab")
			(effects
				(font
					(size 1.27 1.27)
				)
			)
		)
		(duplicate_pad_numbers_are_jumpers no)
		(fp_line
			(start -0.7874 -0.4064)
			(end 0.7874 -0.4064)
			(stroke
				(width 0.1524)
				(type default)
			)
			(layer "F.SilkS")
		)
		(fp_line
			(start -0.7874 0.4064)
			(end -0.7874 -0.4064)
			(stroke
				(width 0.1524)
				(type default)
			)
			(layer "F.SilkS")
		)
		(fp_line
			(start 0.7874 -0.4064)
			(end 0.7874 0.4064)
			(stroke
				(width 0.1524)
				(type default)
			)
			(layer "F.SilkS")
		)
		(fp_line
			(start 0.7874 0.4064)
			(end -0.7874 0.4064)
			(stroke
				(width 0.1524)
				(type default)
			)
			(layer "F.SilkS")
		)
		(fp_line
			(start -0.67945 -0.305054)
			(end -0.12065 -0.305054)
			(stroke
				(width 0.1)
				(type default)
			)
			(layer "F.Fab")
		)
		(fp_line
			(start -0.67945 0.3048)
			(end -0.67945 -0.305054)
			(stroke
				(width 0.1)
				(type default)
			)
			(layer "F.Fab")
		)
		(fp_line
			(start -0.12065 -0.305054)
			(end -0.12065 -0.2794)
			(stroke
				(width 0.1)
				(type default)
			)
			(layer "F.Fab")
		)
		(fp_line
			(start -0.12065 -0.2794)
			(end 0.12065 -0.2794)
			(stroke
				(width 0.1)
				(type default)
			)
			(layer "F.Fab")
		)
		(fp_line
			(start -0.12065 0.2794)
			(end -0.12065 0.3048)
			(stroke
				(width 0.1)
				(type default)
			)
			(layer "F.Fab")
		)
		(fp_line
			(start -0.12065 0.3048)
			(end -0.67945 0.3048)
			(stroke
				(width 0.1)
				(type default)
			)
			(layer "F.Fab")
		)
		(fp_line
			(start 0.120396 0.2794)
			(end -0.12065 0.2794)
			(stroke
				(width 0.1)
				(type default)
			)
			(layer "F.Fab")
		)
		(fp_line
			(start 0.120396 0.3048)
			(end 0.120396 0.2794)
			(stroke
				(width 0.1)
				(type default)
			)
			(layer "F.Fab")
		)
		(fp_line
			(start 0.12065 -0.3048)
			(end 0.67945 -0.3048)
			(stroke
				(width 0.1)
				(type default)
			)
			(layer "F.Fab")
		)
		(fp_line
			(start 0.12065 -0.2794)
			(end 0.12065 -0.3048)
			(stroke
				(width 0.1)
				(type default)
			)
			(layer "F.Fab")
		)
		(fp_line
			(start 0.67945 -0.3048)
			(end 0.67945 0.3048)
			(stroke
				(width 0.1)
				(type default)
			)
			(layer "F.Fab")
		)
		(fp_line
			(start 0.67945 0.3048)
			(end 0.120396 0.3048)
			(stroke
				(width 0.1)
				(type default)
			)
			(layer "F.Fab")
		)
		(pad "1" smd circle
			(at -0.40005 0)
			(size 0 0)
			(layers "F.Cu" "F.Mask" "F.Paste")
			(net "P12V_SCM_GATE")
		)
		(pad "2" smd circle
			(at 0.40005 0)
			(size 0 0)
			(layers "F.Cu" "F.Mask" "F.Paste")
			(net "GND")
		)
	)
	(footprint ""
		(layer "F.Cu")
		(at 130.946906 -21.372068 90)
		(property "Reference" "R3254"
			(at 0 0 90)
			(layer "F.SilkS")
			(hide yes)
			(effects
				(font
					(size 1.27 1.27)
				)
			)
		)
		(property "Value" ""
			(at 0 0 90)
			(layer "F.Fab")
			(effects
				(font
					(size 1.27 1.27)
				)
			)
		)
		(duplicate_pad_numbers_are_jumpers no)
		(fp_line
			(start 0.7874 -0.4064)
			(end 0.7874 0.4064)
			(stroke
				(width 0.1524)
				(type default)
			)
			(layer "F.SilkS")
		)
		(fp_line
			(start -0.7874 -0.4064)
			(end 0.7874 -0.4064)
			(stroke
				(width 0.1524)
				(type default)
			)
			(layer "F.SilkS")
		)
		(fp_line
			(start 0.7874 0.4064)
			(end -0.7874 0.4064)
			(stroke
				(width 0.1524)
				(type default)
			)
			(layer "F.SilkS")
		)
		(fp_line
			(start -0.7874 0.4064)
			(end -0.7874 -0.4064)
			(stroke
				(width 0.1524)
				(type default)
			)
			(layer "F.SilkS")
		)
		(fp_line
			(start -0.12065 -0.305054)
			(end -0.12065 -0.2794)
			(stroke
				(width 0.1)
				(type default)
			)
			(layer "F.Fab")
		)
		(fp_line
			(start -0.67945 -0.305054)
			(end -0.12065 -0.305054)
			(stroke
				(width 0.1)
				(type default)
			)
			(layer "F.Fab")
		)
		(fp_line
			(start 0.67945 -0.3048)
			(end 0.67945 0.3048)
			(stroke
				(width 0.1)
				(type default)
			)
			(layer "F.Fab")
		)
		(fp_line
			(start 0.12065 -0.3048)
			(end 0.67945 -0.3048)
			(stroke
				(width 0.1)
				(type default)
			)
			(layer "F.Fab")
		)
		(fp_line
			(start 0.12065 -0.2794)
			(end 0.12065 -0.3048)
			(stroke
				(width 0.1)
				(type default)
			)
			(layer "F.Fab")
		)
		(fp_line
			(start -0.12065 -0.2794)
			(end 0.12065 -0.2794)
			(stroke
				(width 0.1)
				(type default)
			)
			(layer "F.Fab")
		)
		(fp_line
			(start 0.120396 0.2794)
			(end -0.12065 0.2794)
			(stroke
				(width 0.1)
				(type default)
			)
			(layer "F.Fab")
		)
		(fp_line
			(start -0.12065 0.2794)
			(end -0.12065 0.3048)
			(stroke
				(width 0.1)
				(type default)
			)
			(layer "F.Fab")
		)
		(fp_line
			(start 0.67945 0.3048)
			(end 0.120396 0.3048)
			(stroke
				(width 0.1)
				(type default)
			)
			(layer "F.Fab")
		)
		(fp_line
			(start 0.120396 0.3048)
			(end 0.120396 0.2794)
			(stroke
				(width 0.1)
				(type default)
			)
			(layer "F.Fab")
		)
		(fp_line
			(start -0.12065 0.3048)
			(end -0.67945 0.3048)
			(stroke
				(width 0.1)
				(type default)
			)
			(layer "F.Fab")
		)
		(fp_line
			(start -0.67945 0.3048)
			(end -0.67945 -0.305054)
			(stroke
				(width 0.1)
				(type default)
			)
			(layer "F.Fab")
		)
		(pad "1" smd circle
			(at -0.40005 0 90)
			(size 0 0)
			(layers "F.Cu" "F.Mask" "F.Paste")
			(net "TP_PCIE_TXP<3>")
		)
		(pad "2" smd circle
			(at 0.40005 0 90)
			(size 0 0)
			(layers "F.Cu" "F.Mask" "F.Paste")
			(net "LED_HDD_ACTIVITY_B_N")
		)
	)
)
